# T6G (Grand Teton) — schematic netlist excerpt (pin names and nets, part order shuffled) for the footprints in the layout excerpt that follows; sources: Cadence DE-HDL packaged netlist, KiCad conversion of 04192023_DAF0TMB3IC0_F0TG_MB_C_brd_V02_OCP.brd

PC2085  Q_CAP  1UF 25V 10% X6S  pkg C0402  page 134 : A = P12V_OCP_VCC_1 ; B = GND
R3627  Q_RES  4.7K 1% CHIP  pkg 0402LF  page 236 : A = P3V3_AUX ; B = INA230_1_A0

(kicad_pcb
	(version 20260206)
	(generator "pcbnew")
	(generator_version "10.0")
	(general
		(thickness 1.6)
		(legacy_teardrops no)
	)
	(paper "A4")
	(title_block
		(title "04192023_DAF0TMB3IC0_F0TG_MB_C_brd_V02_OCP.brd")
		(comment 1 "Grand Teton / footprints 2881-2882 of 8354")
	)
	(layers
		(0 "F.Cu" signal "TOP")
		(4 "In1.Cu" signal "GND")
		(6 "In2.Cu" signal "IN1")
		(8 "In3.Cu" signal "GND1")
		(10 "In4.Cu" signal "IN2")
		(12 "In5.Cu" signal "GND2")
		(14 "In6.Cu" signal "IN3")
		(16 "In7.Cu" signal "GND3")
		(18 "In8.Cu" signal "VCC")
		(20 "In9.Cu" signal "VCC1")
		(22 "In10.Cu" signal "GND4")
		(24 "In11.Cu" signal "IN4")
		(26 "In12.Cu" signal "GND5")
		(28 "In13.Cu" signal "IN5")
		(30 "In14.Cu" signal "GND6")
		(32 "In15.Cu" signal "IN6")
		(34 "In16.Cu" signal "GND7")
		(2 "B.Cu" signal "BOTTOM")
		(9 "F.Adhes" user "F.Adhesive")
		(11 "B.Adhes" user "B.Adhesive")
		(13 "F.Paste" user "Package Geometry/Pastemask Top")
		(15 "B.Paste" user "Package Geometry/Pastemask Bottom")
		(5 "F.SilkS" user "Ref Des/Silkscreen Top")
		(7 "B.SilkS" user "Ref Des/Silkscreen Bottom")
		(1 "F.Mask" user "Board Geometry/Soldermask Top")
		(3 "B.Mask" user "Board Geometry/Soldermask Bottom")
		(17 "Dwgs.User" user "User.Drawings")
		(19 "Cmts.User" user "User.Comments")
		(21 "Eco1.User" user "User.Eco1")
		(23 "Eco2.User" user "User.Eco2")
		(25 "Edge.Cuts" user "Board Geometry/Outline")
		(27 "Margin" user)
		(31 "F.CrtYd" user "Package Geometry/Place Bound Top")
		(29 "B.CrtYd" user "Package Geometry/Place Bound Bottom")
		(35 "F.Fab" user "Ref Des/Assembly Top")
		(33 "B.Fab" user "Ref Des/Assembly Bottom")
	)
	(footprint ""
		(layer "F.Cu")
		(at 449.650612 -23.594314 180)
		(property "Reference" "PC2085"
			(at 0 0 180)
			(layer "F.SilkS")
			(hide yes)
			(effects
				(font
					(size 1.27 1.27)
				)
			)
		)
		(property "Value" ""
			(at 0 0 180)
			(layer "F.Fab")
			(effects
				(font
					(size 1.27 1.27)
				)
			)
		)
		(duplicate_pad_numbers_are_jumpers no)
		(fp_line
			(start 0.7874 0.4064)
			(end -0.7874 0.4064)
			(stroke
				(width 0.1524)
				(type default)
			)
			(layer "F.SilkS")
		)
		(fp_line
			(start 0.7874 -0.4064)
			(end 0.7874 0.4064)
			(stroke
				(width 0.1524)
				(type default)
			)
			(layer "F.SilkS")
		)
		(fp_line
			(start -0.7874 0.4064)
			(end -0.7874 -0.4064)
			(stroke
				(width 0.1524)
				(type default)
			)
			(layer "F.SilkS")
		)
		(fp_line
			(start -0.7874 -0.4064)
			(end 0.7874 -0.4064)
			(stroke
				(width 0.1524)
				(type default)
			)
			(layer "F.SilkS")
		)
		(fp_line
			(start 0.67945 0.3048)
			(end 0.120396 0.3048)
			(stroke
				(width 0.1)
				(type default)
			)
			(layer "F.Fab")
		)
		(fp_line
			(start 0.67945 -0.3048)
			(end 0.67945 0.3048)
			(stroke
				(width 0.1)
				(type default)
			)
			(layer "F.Fab")
		)
		(fp_line
			(start 0.12065 -0.2794)
			(end 0.12065 -0.3048)
			(stroke
				(width 0.1)
				(type default)
			)
			(layer "F.Fab")
		)
		(fp_line
			(start 0.12065 -0.3048)
			(end 0.67945 -0.3048)
			(stroke
				(width 0.1)
				(type default)
			)
			(layer "F.Fab")
		)
		(fp_line
			(start 0.120396 0.3048)
			(end 0.120396 0.2794)
			(stroke
				(width 0.1)
				(type default)
			)
			(layer "F.Fab")
		)
		(fp_line
			(start 0.120396 0.2794)
			(end -0.12065 0.2794)
			(stroke
				(width 0.1)
				(type default)
			)
			(layer "F.Fab")
		)
		(fp_line
			(start -0.12065 0.3048)
			(end -0.67945 0.3048)
			(stroke
				(width 0.1)
				(type default)
			)
			(layer "F.Fab")
		)
		(fp_line
			(start -0.12065 0.2794)
			(end -0.12065 0.3048)
			(stroke
				(width 0.1)
				(type default)
			)
			(layer "F.Fab")
		)
		(fp_line
			(start -0.12065 -0.2794)
			(end 0.12065 -0.2794)
			(stroke
				(width 0.1)
				(type default)
			)
			(layer "F.Fab")
		)
		(fp_line
			(start -0.12065 -0.305054)
			(end -0.12065 -0.2794)
			(stroke
				(width 0.1)
				(type default)
			)
			(layer "F.Fab")
		)
		(fp_line
			(start -0.67945 0.3048)
			(end -0.67945 -0.305054)
			(stroke
				(width 0.1)
				(type default)
			)
			(layer "F.Fab")
		)
		(fp_line
			(start -0.67945 -0.305054)
			(end -0.12065 -0.305054)
			(stroke
				(width 0.1)
				(type default)
			)
			(layer "F.Fab")
		)
		(pad "1" smd circle
			(at -0.40005 0 180)
			(size 0 0)
			(layers "F.Cu" "F.Mask" "F.Paste")
			(net "P12V_OCP_VCC_1")
		)
		(pad "2" smd circle
			(at 0.40005 0 180)
			(size 0 0)
			(layers "F.Cu" "F.Mask" "F.Paste")
			(net "GND")
		)
	)
	(footprint ""
		(layer "F.Cu")
		(at 445.157098 -93.484192 180)
		(property "Reference" "R3627"
			(at 0 0 180)
			(layer "F.SilkS")
			(hide yes)
			(effects
				(font
					(size 1.27 1.27)
				)
			)
		)
		(property "Value" ""
			(at 0 0 180)
			(layer "F.Fab")
			(effects
				(font
					(size 1.27 1.27)
				)
			)
		)
		(duplicate_pad_numbers_are_jumpers no)
		(fp_line
			(start 0.7874 0.4064)
			(end -0.7874 0.4064)
			(stroke
				(width 0.1524)
				(type default)
			)
			(layer "F.SilkS")
		)
		(fp_line
			(start 0.7874 -0.4064)
			(end 0.7874 0.4064)
			(stroke
				(width 0.1524)
				(type default)
			)
			(layer "F.SilkS")
		)
		(fp_line
			(start -0.7874 0.4064)
			(end -0.7874 -0.4064)
			(stroke
				(width 0.1524)
				(type default)
			)
			(layer "F.SilkS")
		)
		(fp_line
			(start -0.7874 -0.4064)
			(end 0.7874 -0.4064)
			(stroke
				(width 0.1524)
				(type default)
			)
			(layer "F.SilkS")
		)
		(fp_line
			(start 0.67945 0.3048)
			(end 0.120396 0.3048)
			(stroke
				(width 0.1)
				(type default)
			)
			(layer "F.Fab")
		)
		(fp_line
			(start 0.67945 -0.3048)
			(end 0.67945 0.3048)
			(stroke
				(width 0.1)
				(type default)
			)
			(layer "F.Fab")
		)
		(fp_line
			(start 0.12065 -0.2794)
			(end 0.12065 -0.3048)
			(stroke
				(width 0.1)
				(type default)
			)
			(layer "F.Fab")
		)
		(fp_line
			(start 0.12065 -0.3048)
			(end 0.67945 -0.3048)
			(stroke
				(width 0.1)
				(type default)
			)
			(layer "F.Fab")
		)
		(fp_line
			(start 0.120396 0.3048)
			(end 0.120396 0.2794)
			(stroke
				(width 0.1)
				(type default)
			)
			(layer "F.Fab")
		)
		(fp_line
			(start 0.120396 0.2794)
			(end -0.12065 0.2794)
			(stroke
				(width 0.1)
				(type default)
			)
			(layer "F.Fab")
		)
		(fp_line
			(start -0.12065 0.3048)
			(end -0.67945 0.3048)
			(stroke
				(width 0.1)
				(type default)
			)
			(layer "F.Fab")
		)
		(fp_line
			(start -0.12065 0.2794)
			(end -0.12065 0.3048)
			(stroke
				(width 0.1)
				(type default)
			)
			(layer "F.Fab")
		)
		(fp_line
			(start -0.12065 -0.2794)
			(end 0.12065 -0.2794)
			(stroke
				(width 0.1)
				(type default)
			)
			(layer "F.Fab")
		)
		(fp_line
			(start -0.12065 -0.305054)
			(end -0.12065 -0.2794)
			(stroke
				(width 0.1)
				(type default)
			)
			(layer "F.Fab")
		)
		(fp_line
			(start -0.67945 0.3048)
			(end -0.67945 -0.305054)
			(stroke
				(width 0.1)
				(type default)
			)
			(layer "F.Fab")
		)
		(fp_line
			(start -0.67945 -0.305054)
			(end -0.12065 -0.305054)
			(stroke
				(width 0.1)
				(type default)
			)
			(layer "F.Fab")
		)
		(pad "1" smd circle
			(at -0.40005 0 180)
			(size 0 0)
			(layers "F.Cu" "F.Mask" "F.Paste")
			(net "P3V3_AUX")
		)
		(pad "2" smd circle
			(at 0.40005 0 180)
			(size 0 0)
			(layers "F.Cu" "F.Mask" "F.Paste")
			(net "INA230_1_A0")
		)
	)
)
